(kicad_pcb
	(version 20260206)
	(generator "pcbnew")
	(generator_version "10.0")
	(general
		(thickness 1.6)
		(legacy_teardrops no)
	)
	(paper "A4")
	(title_block
		(title "01162023_DA0F0TEBIF0_F0T_Expander_BD_F_brd_V02_OCP.brd")
		(comment 1 "Grand Teton / footprint 6619 of 9728 (PEX0), pads 117-233 of 2397")
	)
	(layers
		(0 "F.Cu" signal "TOP")
		(4 "In1.Cu" signal "GND")
		(6 "In2.Cu" signal "VCC")
		(8 "In3.Cu" signal "VCC1")
		(10 "In4.Cu" signal "GND1")
		(12 "In5.Cu" signal "IN1")
		(14 "In6.Cu" signal "GND2")
		(16 "In7.Cu" signal "IN2")
		(18 "In8.Cu" signal "GND3")
		(20 "In9.Cu" signal "IN3")
		(22 "In10.Cu" signal "GND4")
		(24 "In11.Cu" signal "IN4")
		(26 "In12.Cu" signal "GND5")
		(28 "In13.Cu" signal "IN5")
		(30 "In14.Cu" signal "GND6")
		(32 "In15.Cu" signal "IN6")
		(34 "In16.Cu" signal "GND7")
		(2 "B.Cu" signal "BOTTOM")
		(9 "F.Adhes" user "F.Adhesive")
		(11 "B.Adhes" user "B.Adhesive")
		(13 "F.Paste" user "Package Geometry/Pastemask Top")
		(15 "B.Paste" user "Package Geometry/Pastemask Bottom")
		(5 "F.SilkS" user "Ref Des/Silkscreen Top")
		(7 "B.SilkS" user "Ref Des/Silkscreen Bottom")
		(1 "F.Mask" user "Board Geometry/Soldermask Top")
		(3 "B.Mask" user "Board Geometry/Soldermask Bottom")
		(17 "Dwgs.User" user "User.Drawings")
		(19 "Cmts.User" user "User.Comments")
		(21 "Eco1.User" user "User.Eco1")
		(23 "Eco2.User" user "User.Eco2")
		(25 "Edge.Cuts" user "Board Geometry/Outline")
		(27 "Margin" user)
		(31 "F.CrtYd" user "Package Geometry/Place Bound Top")
		(29 "B.CrtYd" user "Package Geometry/Place Bound Bottom")
		(35 "F.Fab" user "Ref Des/Assembly Top")
		(33 "B.Fab" user "Ref Des/Assembly Bottom")
	)
	(footprint ""
		(layer "F.Cu")
		(at 59.649868 -295.89984)
		(property "Reference" "PEX0"
			(at -3.360166 35.566858 0)
			(unlocked yes)
			(layer "F.SilkS")
			(effects
				(font
					(size 2.032 1.524)
					(thickness 0.1524)
				)
				(justify left)
			)
		)
		(property "Value" ""
			(at 0 0 0)
			(layer "F.Fab")
			(effects
				(font
					(size 1.27 1.27)
				)
			)
		)
		(duplicate_pad_numbers_are_jumpers no)
		(pad "AB21" smd circle
			(at -3.800094 -2.84988)
			(size 0.4572 0.4572)
			(layers "F.Cu" "F.Mask" "F.Paste")
			(net "P0V8_SERDES_VDDA_PEX0")
		)
		(pad "AB22" smd circle
			(at -2.84988 -2.84988)
			(size 0.4572 0.4572)
			(layers "F.Cu" "F.Mask" "F.Paste")
			(net "P0V8_SERDES_VDDA_PEX0")
		)
		(pad "AB23" smd circle
			(at -1.89992 -2.84988)
			(size 0.4572 0.4572)
			(layers "F.Cu" "F.Mask" "F.Paste")
			(net "P0V8_SERDES_VDDA_PEX0")
		)
		(pad "AB24" smd circle
			(at -0.94996 -2.84988)
			(size 0.4572 0.4572)
			(layers "F.Cu" "F.Mask" "F.Paste")
			(net "P0V8_SERDES_VDDA_PEX0")
		)
		(pad "AB25" smd circle
			(at 0 -2.84988)
			(size 0.4572 0.4572)
			(layers "F.Cu" "F.Mask" "F.Paste")
			(net "P0V8_SERDES_VDDA_PEX0")
		)
		(pad "AB26" smd circle
			(at 0.94996 -2.84988)
			(size 0.4572 0.4572)
			(layers "F.Cu" "F.Mask" "F.Paste")
			(net "P0V8_SERDES_VDDA_PEX0")
		)
		(pad "AB27" smd circle
			(at 1.89992 -2.84988)
			(size 0.4572 0.4572)
			(layers "F.Cu" "F.Mask" "F.Paste")
			(net "P0V8_SERDES_VDDA_PEX0")
		)
		(pad "AB28" smd circle
			(at 2.84988 -2.84988)
			(size 0.4572 0.4572)
			(layers "F.Cu" "F.Mask" "F.Paste")
			(net "P0V8_SERDES_VDDA_PEX0")
		)
		(pad "AB29" smd circle
			(at 3.800094 -2.84988)
			(size 0.4572 0.4572)
			(layers "F.Cu" "F.Mask" "F.Paste")
			(net "P0V8_SERDES_VDDA_PEX0")
		)
		(pad "AB30" smd circle
			(at 4.750054 -2.84988)
			(size 0.4572 0.4572)
			(layers "F.Cu" "F.Mask" "F.Paste")
			(net "P0V8_SERDES_VDDA_PEX0")
		)
		(pad "AB31" smd circle
			(at 5.700014 -2.84988)
			(size 0.4572 0.4572)
			(layers "F.Cu" "F.Mask" "F.Paste")
			(net "P0V8_SERDES_VDDA_PEX0")
		)
		(pad "AB32" smd circle
			(at 6.649974 -2.84988)
			(size 0.4572 0.4572)
			(layers "F.Cu" "F.Mask" "F.Paste")
			(net "P0V8_SERDES_VDDA_PEX0")
		)
		(pad "AB33" smd circle
			(at 7.599934 -2.84988)
			(size 0.4572 0.4572)
			(layers "F.Cu" "F.Mask" "F.Paste")
			(net "P0V8_SERDES_VDDA_PEX0")
		)
		(pad "AB34" smd circle
			(at 8.549894 -2.84988)
			(size 0.4572 0.4572)
			(layers "F.Cu" "F.Mask" "F.Paste")
			(net "GND")
		)
		(pad "AB35" smd circle
			(at 9.500108 -2.84988)
			(size 0.4572 0.4572)
			(layers "F.Cu" "F.Mask" "F.Paste")
			(net "Net_481")
		)
		(pad "AB36" smd circle
			(at 10.450068 -2.84988)
			(size 0.4572 0.4572)
			(layers "F.Cu" "F.Mask" "F.Paste")
			(net "GND")
		)
		(pad "AB37" smd circle
			(at 11.400028 -2.84988)
			(size 0.4572 0.4572)
			(layers "F.Cu" "F.Mask" "F.Paste")
			(net "GND")
		)
		(pad "AB38" smd circle
			(at 12.349988 -2.84988)
			(size 0.4572 0.4572)
			(layers "F.Cu" "F.Mask" "F.Paste")
			(net "GND")
		)
		(pad "AB39" smd circle
			(at 13.299948 -2.84988)
			(size 0.4572 0.4572)
			(layers "F.Cu" "F.Mask" "F.Paste")
			(net "GND")
		)
		(pad "AB40" smd circle
			(at 14.249908 -2.84988)
			(size 0.4572 0.4572)
			(layers "F.Cu" "F.Mask" "F.Paste")
			(net "GND")
		)
		(pad "AB41" smd circle
			(at 15.200122 -2.84988)
			(size 0.4572 0.4572)
			(layers "F.Cu" "F.Mask" "F.Paste")
			(net "Net_2819")
		)
		(pad "AB42" smd circle
			(at 16.150082 -2.84988)
			(size 0.4572 0.4572)
			(layers "F.Cu" "F.Mask" "F.Paste")
			(net "Net_2803")
		)
		(pad "AB43" smd circle
			(at 17.100042 -2.84988)
			(size 0.4572 0.4572)
			(layers "F.Cu" "F.Mask" "F.Paste")
			(net "GND")
		)
		(pad "AB44" smd circle
			(at 18.050002 -2.84988)
			(size 0.4572 0.4572)
			(layers "F.Cu" "F.Mask" "F.Paste")
			(net "GND")
		)
		(pad "AB45" smd circle
			(at 18.999962 -2.84988)
			(size 0.4572 0.4572)
			(layers "F.Cu" "F.Mask" "F.Paste")
			(net "GND")
		)
		(pad "AB46" smd circle
			(at 19.949922 -2.84988)
			(size 0.4572 0.4572)
			(layers "F.Cu" "F.Mask" "F.Paste")
			(net "GND")
		)
		(pad "AB47" smd circle
			(at 20.899882 -2.84988)
			(size 0.4572 0.4572)
			(layers "F.Cu" "F.Mask" "F.Paste")
			(net "GND")
		)
		(pad "AB48" smd circle
			(at 21.850096 -2.84988)
			(size 0.4572 0.4572)
			(layers "F.Cu" "F.Mask" "F.Paste")
			(net "Net_2787")
		)
		(pad "AB49" smd circle
			(at 22.800056 -2.84988)
			(size 0.4572 0.4572)
			(layers "F.Cu" "F.Mask" "F.Paste")
			(net "Net_2771")
		)
		(pad "AC1" smd circle
			(at -22.800056 -1.89992)
			(size 0.4572 0.4572)
			(layers "F.Cu" "F.Mask" "F.Paste")
			(net "CLK_100M_DB2000QL_PEX0_S1_R_DN")
		)
		(pad "AC2" smd circle
			(at -21.850096 -1.89992)
			(size 0.4572 0.4572)
			(layers "F.Cu" "F.Mask" "F.Paste")
			(net "CLK_100M_DB2000QL_PEX0_S1_R_DP")
		)
		(pad "AC3" smd circle
			(at -20.899882 -1.89992)
			(size 0.4572 0.4572)
			(layers "F.Cu" "F.Mask" "F.Paste")
			(net "GND")
		)
		(pad "AC4" smd circle
			(at -19.949922 -1.89992)
			(size 0.4572 0.4572)
			(layers "F.Cu" "F.Mask" "F.Paste")
			(net "GND")
		)
		(pad "AC5" smd circle
			(at -18.999962 -1.89992)
			(size 0.4572 0.4572)
			(layers "F.Cu" "F.Mask" "F.Paste")
			(net "GND")
		)
		(pad "AC6" smd circle
			(at -18.050002 -1.89992)
			(size 0.4572 0.4572)
			(layers "F.Cu" "F.Mask" "F.Paste")
			(net "GND")
		)
		(pad "AC7" smd circle
			(at -17.100042 -1.89992)
			(size 0.4572 0.4572)
			(layers "F.Cu" "F.Mask" "F.Paste")
			(net "Net_2916")
		)
		(pad "AC8" smd circle
			(at -16.150082 -1.89992)
			(size 0.4572 0.4572)
			(layers "F.Cu" "F.Mask" "F.Paste")
			(net "Net_2918")
		)
		(pad "AC9" smd circle
			(at -15.200122 -1.89992)
			(size 0.4572 0.4572)
			(layers "F.Cu" "F.Mask" "F.Paste")
			(net "GND")
		)
		(pad "AC10" smd circle
			(at -14.249908 -1.89992)
			(size 0.4572 0.4572)
			(layers "F.Cu" "F.Mask" "F.Paste")
			(net "P1V8_VDDA_PEX0")
		)
		(pad "AC11" smd circle
			(at -13.299948 -1.89992)
			(size 0.4572 0.4572)
			(layers "F.Cu" "F.Mask" "F.Paste")
			(net "GND")
		)
		(pad "AC12" smd circle
			(at -12.349988 -1.89992)
			(size 0.4572 0.4572)
			(layers "F.Cu" "F.Mask" "F.Paste")
			(net "GND")
		)
		(pad "AC13" smd circle
			(at -11.400028 -1.89992)
			(size 0.4572 0.4572)
			(layers "F.Cu" "F.Mask" "F.Paste")
			(net "SYSPLL_VDDA18_PEX0")
		)
		(pad "AC14" smd circle
			(at -10.450068 -1.89992)
			(size 0.4572 0.4572)
			(layers "F.Cu" "F.Mask" "F.Paste")
			(net "GND")
		)
		(pad "AC15" smd circle
			(at -9.500108 -1.89992)
			(size 0.4572 0.4572)
			(layers "F.Cu" "F.Mask" "F.Paste")
			(net "P0V8_PEX0")
		)
		(pad "AC16" smd circle
			(at -8.549894 -1.89992)
			(size 0.4572 0.4572)
			(layers "F.Cu" "F.Mask" "F.Paste")
			(net "GND")
		)
		(pad "AC17" smd circle
			(at -7.599934 -1.89992)
			(size 0.4572 0.4572)
			(layers "F.Cu" "F.Mask" "F.Paste")
			(net "P0V8_PEX0")
		)
		(pad "AC18" smd circle
			(at -6.649974 -1.89992)
			(size 0.4572 0.4572)
			(layers "F.Cu" "F.Mask" "F.Paste")
			(net "GND")
		)
		(pad "AC19" smd circle
			(at -5.700014 -1.89992)
			(size 0.4572 0.4572)
			(layers "F.Cu" "F.Mask" "F.Paste")
			(net "P0V8_PEX0")
		)
		(pad "AC20" smd circle
			(at -4.750054 -1.89992)
			(size 0.4572 0.4572)
			(layers "F.Cu" "F.Mask" "F.Paste")
			(net "GND")
		)
		(pad "AC21" smd circle
			(at -3.800094 -1.89992)
			(size 0.4572 0.4572)
			(layers "F.Cu" "F.Mask" "F.Paste")
			(net "P0V8_PEX0")
		)
		(pad "AC22" smd circle
			(at -2.84988 -1.89992)
			(size 0.4572 0.4572)
			(layers "F.Cu" "F.Mask" "F.Paste")
			(net "GND")
		)
		(pad "AC23" smd circle
			(at -1.89992 -1.89992)
			(size 0.4572 0.4572)
			(layers "F.Cu" "F.Mask" "F.Paste")
			(net "P0V8_PEX0")
		)
		(pad "AC24" smd circle
			(at -0.94996 -1.89992)
			(size 0.4572 0.4572)
			(layers "F.Cu" "F.Mask" "F.Paste")
			(net "GND")
		)
		(pad "AC25" smd circle
			(at 0 -1.89992)
			(size 0.4572 0.4572)
			(layers "F.Cu" "F.Mask" "F.Paste")
			(net "P0V8_PEX0")
		)
		(pad "AC26" smd circle
			(at 0.94996 -1.89992)
			(size 0.4572 0.4572)
			(layers "F.Cu" "F.Mask" "F.Paste")
			(net "GND")
		)
		(pad "AC27" smd circle
			(at 1.89992 -1.89992)
			(size 0.4572 0.4572)
			(layers "F.Cu" "F.Mask" "F.Paste")
			(net "P0V8_PEX0")
		)
		(pad "AC28" smd circle
			(at 2.84988 -1.89992)
			(size 0.4572 0.4572)
			(layers "F.Cu" "F.Mask" "F.Paste")
			(net "GND")
		)
		(pad "AC29" smd circle
			(at 3.800094 -1.89992)
			(size 0.4572 0.4572)
			(layers "F.Cu" "F.Mask" "F.Paste")
			(net "P0V8_PEX0")
		)
		(pad "AC30" smd circle
			(at 4.750054 -1.89992)
			(size 0.4572 0.4572)
			(layers "F.Cu" "F.Mask" "F.Paste")
			(net "GND")
		)
		(pad "AC31" smd circle
			(at 5.700014 -1.89992)
			(size 0.4572 0.4572)
			(layers "F.Cu" "F.Mask" "F.Paste")
			(net "P0V8_PEX0")
		)
		(pad "AC32" smd circle
			(at 6.649974 -1.89992)
			(size 0.4572 0.4572)
			(layers "F.Cu" "F.Mask" "F.Paste")
			(net "GND")
		)
		(pad "AC33" smd circle
			(at 7.599934 -1.89992)
			(size 0.4572 0.4572)
			(layers "F.Cu" "F.Mask" "F.Paste")
			(net "P0V8_PEX0")
		)
		(pad "AC34" smd circle
			(at 8.549894 -1.89992)
			(size 0.4572 0.4572)
			(layers "F.Cu" "F.Mask" "F.Paste")
			(net "GND")
		)
		(pad "AC35" smd circle
			(at 9.500108 -1.89992)
			(size 0.4572 0.4572)
			(layers "F.Cu" "F.Mask" "F.Paste")
			(net "GND")
		)
		(pad "AC36" smd circle
			(at 10.450068 -1.89992)
			(size 0.4572 0.4572)
			(layers "F.Cu" "F.Mask" "F.Paste")
			(net "P1V25_PEX0")
		)
		(pad "AC37" smd circle
			(at 11.400028 -1.89992)
			(size 0.4572 0.4572)
			(layers "F.Cu" "F.Mask" "F.Paste")
			(net "GND")
		)
		(pad "AC38" smd circle
			(at 12.349988 -1.89992)
			(size 0.4572 0.4572)
			(layers "F.Cu" "F.Mask" "F.Paste")
			(net "P1V25_SERDES_VDDPLL_PEX0")
		)
		(pad "AC39" smd circle
			(at 13.299948 -1.89992)
			(size 0.4572 0.4572)
			(layers "F.Cu" "F.Mask" "F.Paste")
			(net "GND")
		)
		(pad "AC40" smd circle
			(at 14.249908 -1.89992)
			(size 0.4572 0.4572)
			(layers "F.Cu" "F.Mask" "F.Paste")
			(net "GND")
		)
		(pad "AC41" smd circle
			(at 15.200122 -1.89992)
			(size 0.4572 0.4572)
			(layers "F.Cu" "F.Mask" "F.Paste")
			(net "GND")
		)
		(pad "AC42" smd circle
			(at 16.150082 -1.89992)
			(size 0.4572 0.4572)
			(layers "F.Cu" "F.Mask" "F.Paste")
			(net "GND")
		)
		(pad "AC43" smd circle
			(at 17.100042 -1.89992)
			(size 0.4572 0.4572)
			(layers "F.Cu" "F.Mask" "F.Paste")
			(net "Net_2820")
		)
		(pad "AC44" smd circle
			(at 18.050002 -1.89992)
			(size 0.4572 0.4572)
			(layers "F.Cu" "F.Mask" "F.Paste")
			(net "Net_2804")
		)
		(pad "AC45" smd circle
			(at 18.999962 -1.89992)
			(size 0.4572 0.4572)
			(layers "F.Cu" "F.Mask" "F.Paste")
			(net "GND")
		)
		(pad "AC46" smd circle
			(at 19.949922 -1.89992)
			(size 0.4572 0.4572)
			(layers "F.Cu" "F.Mask" "F.Paste")
			(net "Net_2788")
		)
		(pad "AC47" smd circle
			(at 20.899882 -1.89992)
			(size 0.4572 0.4572)
			(layers "F.Cu" "F.Mask" "F.Paste")
			(net "Net_2772")
		)
		(pad "AC48" smd circle
			(at 21.850096 -1.89992)
			(size 0.4572 0.4572)
			(layers "F.Cu" "F.Mask" "F.Paste")
			(net "GND")
		)
		(pad "AC49" smd circle
			(at 22.800056 -1.89992)
			(size 0.4572 0.4572)
			(layers "F.Cu" "F.Mask" "F.Paste")
			(net "GND")
		)
		(pad "AD1" smd circle
			(at -22.800056 -0.94996)
			(size 0.4572 0.4572)
			(layers "F.Cu" "F.Mask" "F.Paste")
			(net "GND")
		)
		(pad "AD2" smd circle
			(at -21.850096 -0.94996)
			(size 0.4572 0.4572)
			(layers "F.Cu" "F.Mask" "F.Paste")
			(net "GND")
		)
		(pad "AD3" smd circle
			(at -20.899882 -0.94996)
			(size 0.4572 0.4572)
			(layers "F.Cu" "F.Mask" "F.Paste")
			(net "GND")
		)
		(pad "AD4" smd circle
			(at -19.949922 -0.94996)
			(size 0.4572 0.4572)
			(layers "F.Cu" "F.Mask" "F.Paste")
			(net "Net_387")
		)
		(pad "AD5" smd circle
			(at -18.999962 -0.94996)
			(size 0.4572 0.4572)
			(layers "F.Cu" "F.Mask" "F.Paste")
			(net "Net_384")
		)
		(pad "AD6" smd circle
			(at -18.050002 -0.94996)
			(size 0.4572 0.4572)
			(layers "F.Cu" "F.Mask" "F.Paste")
			(net "GND")
		)
		(pad "AD7" smd circle
			(at -17.100042 -0.94996)
			(size 0.4572 0.4572)
			(layers "F.Cu" "F.Mask" "F.Paste")
			(net "Net_2915")
		)
		(pad "AD8" smd circle
			(at -16.150082 -0.94996)
			(size 0.4572 0.4572)
			(layers "F.Cu" "F.Mask" "F.Paste")
			(net "Net_2917")
		)
		(pad "AD9" smd circle
			(at -15.200122 -0.94996)
			(size 0.4572 0.4572)
			(layers "F.Cu" "F.Mask" "F.Paste")
			(net "GND")
		)
		(pad "AD10" smd circle
			(at -14.249908 -0.94996)
			(size 0.4572 0.4572)
			(layers "F.Cu" "F.Mask" "F.Paste")
			(net "GND")
		)
		(pad "AD11" smd circle
			(at -13.299948 -0.94996)
			(size 0.4572 0.4572)
			(layers "F.Cu" "F.Mask" "F.Paste")
			(net "GND")
		)
		(pad "AD12" smd circle
			(at -12.349988 -0.94996)
			(size 0.4572 0.4572)
			(layers "F.Cu" "F.Mask" "F.Paste")
			(net "PCEPLL2_VDDA18_PEX0")
		)
		(pad "AD13" smd circle
			(at -11.400028 -0.94996)
			(size 0.4572 0.4572)
			(layers "F.Cu" "F.Mask" "F.Paste")
			(net "GND")
		)
		(pad "AD14" smd circle
			(at -10.450068 -0.94996)
			(size 0.4572 0.4572)
			(layers "F.Cu" "F.Mask" "F.Paste")
			(net "P0V8_PEX0")
		)
		(pad "AD15" smd circle
			(at -9.500108 -0.94996)
			(size 0.4572 0.4572)
			(layers "F.Cu" "F.Mask" "F.Paste")
			(net "GND")
		)
		(pad "AD16" smd circle
			(at -8.549894 -0.94996)
			(size 0.4572 0.4572)
			(layers "F.Cu" "F.Mask" "F.Paste")
			(net "P0V8_PEX0")
		)
		(pad "AD17" smd circle
			(at -7.599934 -0.94996)
			(size 0.4572 0.4572)
			(layers "F.Cu" "F.Mask" "F.Paste")
			(net "GND")
		)
		(pad "AD18" smd circle
			(at -6.649974 -0.94996)
			(size 0.4572 0.4572)
			(layers "F.Cu" "F.Mask" "F.Paste")
			(net "P0V8_PEX0")
		)
		(pad "AD19" smd circle
			(at -5.700014 -0.94996)
			(size 0.4572 0.4572)
			(layers "F.Cu" "F.Mask" "F.Paste")
			(net "GND")
		)
		(pad "AD20" smd circle
			(at -4.750054 -0.94996)
			(size 0.4572 0.4572)
			(layers "F.Cu" "F.Mask" "F.Paste")
			(net "P0V8_PEX0")
		)
		(pad "AD21" smd circle
			(at -3.800094 -0.94996)
			(size 0.4572 0.4572)
			(layers "F.Cu" "F.Mask" "F.Paste")
			(net "GND")
		)
		(pad "AD22" smd circle
			(at -2.84988 -0.94996)
			(size 0.4572 0.4572)
			(layers "F.Cu" "F.Mask" "F.Paste")
			(net "P0V8_PEX0")
		)
		(pad "AD23" smd circle
			(at -1.89992 -0.94996)
			(size 0.4572 0.4572)
			(layers "F.Cu" "F.Mask" "F.Paste")
			(net "GND")
		)
		(pad "AD24" smd circle
			(at -0.94996 -0.94996)
			(size 0.4572 0.4572)
			(layers "F.Cu" "F.Mask" "F.Paste")
			(net "P0V8_PEX0")
		)
		(pad "AD25" smd circle
			(at 0 -0.94996)
			(size 0.4572 0.4572)
			(layers "F.Cu" "F.Mask" "F.Paste")
			(net "GND")
		)
		(pad "AD26" smd circle
			(at 0.94996 -0.94996)
			(size 0.4572 0.4572)
			(layers "F.Cu" "F.Mask" "F.Paste")
			(net "P0V8_PEX0")
		)
		(pad "AD27" smd circle
			(at 1.89992 -0.94996)
			(size 0.4572 0.4572)
			(layers "F.Cu" "F.Mask" "F.Paste")
			(net "GND")
		)
		(pad "AD28" smd circle
			(at 2.84988 -0.94996)
			(size 0.4572 0.4572)
			(layers "F.Cu" "F.Mask" "F.Paste")
			(net "P0V8_PEX0")
		)
		(pad "AD29" smd circle
			(at 3.800094 -0.94996)
			(size 0.4572 0.4572)
			(layers "F.Cu" "F.Mask" "F.Paste")
			(net "GND")
		)
		(pad "AD30" smd circle
			(at 4.750054 -0.94996)
			(size 0.4572 0.4572)
			(layers "F.Cu" "F.Mask" "F.Paste")
			(net "P0V8_PEX0")
		)
		(pad "AD31" smd circle
			(at 5.700014 -0.94996)
			(size 0.4572 0.4572)
			(layers "F.Cu" "F.Mask" "F.Paste")
			(net "GND")
		)
		(pad "AD32" smd circle
			(at 6.649974 -0.94996)
			(size 0.4572 0.4572)
			(layers "F.Cu" "F.Mask" "F.Paste")
			(net "P0V8_SERDES_VDDA_PEX0")
		)
		(pad "AD33" smd circle
			(at 7.599934 -0.94996)
			(size 0.4572 0.4572)
			(layers "F.Cu" "F.Mask" "F.Paste")
			(net "P0V8_SERDES_VDDA_PEX0")
		)
		(pad "AD34" smd circle
			(at 8.549894 -0.94996)
			(size 0.4572 0.4572)
			(layers "F.Cu" "F.Mask" "F.Paste")
			(net "P0V8_SERDES_VDDA_PEX0")
		)
		(pad "AD35" smd circle
			(at 9.500108 -0.94996)
			(size 0.4572 0.4572)
			(layers "F.Cu" "F.Mask" "F.Paste")
			(net "GND")
		)
		(pad "AD36" smd circle
			(at 10.450068 -0.94996)
			(size 0.4572 0.4572)
			(layers "F.Cu" "F.Mask" "F.Paste")
			(net "P1V25_PEX0")
		)
		(pad "AD37" smd circle
			(at 11.400028 -0.94996)
			(size 0.4572 0.4572)
			(layers "F.Cu" "F.Mask" "F.Paste")
			(net "GND")
		)
		(pad "AD38" smd circle
			(at 12.349988 -0.94996)
			(size 0.4572 0.4572)
			(layers "F.Cu" "F.Mask" "F.Paste")
			(net "P1V25_SERDES_VDDPLL_PEX0")
		)
		(pad "AD39" smd circle
			(at 13.299948 -0.94996)
			(size 0.4572 0.4572)
			(layers "F.Cu" "F.Mask" "F.Paste")
			(net "GND")
		)
	)
)
